FILE_TYPE = CONNECTIVITY;
{Allegro Design Entry HDL 17.2-2016 S081 (4005846) 1/11/2022}
"PAGE_NUMBER" = 144;
0"NC";
1"GND\g";
2"GND\g";
3"PVDD18_S5_P0\g";
4"GND\g";
5"GND\g";
6"GND\g";
7"P1V8_STBY\g";
8"P1V8_STBY\g";
9"P1V8_STBY\g";
10"P1V8_STBY\g";
11"GND\g";
12"P1V8_STBY\g";
13"P1V8_STBY\g";
14"GND\g";
15"P3V3_STBY\g";
16"P3V3_STBY\g";
17"P1V8_STBY\g";
18"PD_BIOS_DEBUG_MODE";
19"P3V3_STBY\g";
20"GND\g";
21"FM_JTAG_BMC_OE";
22"PRSNT_CPU1_N";
23"PU_BIOS_USB_RECOVERY";
24"PRSNT_CPU0_N";
25"PD_SPI_CPU0_CLK";
26"BMC_JTAG_SEL";
27"JTAG_BMC_OE";
28"FM_PRSNT_CPU0_N";
29"BIOS_DEBUG_MODE";
30"FM_BIOS_USB_RECOVERY";
31"BMC_JTAG_SEL";
32"FM_SPD_CPU0_SWITCH_CTRL_N";
33"JTAG_BMC_OE";
34"FM_JTAG_BMC_OE";
35"FM_PASSWORD_CLEAR_N";
36"FM_FORCE_ALL_PWRON";
37"FM_PRSNT_CPU1_N";
38"SPI_CPU0_R1_CLK";
39"BIOS_DEBUG_MODE";
40"SPI_CPU0_CLK";
41"PD_SPI_CPU0_CLK";
42"SPI_CPU0_CLK";
43"FM_SPD_CPU0_SWITCH_CTRL_N";
44"FM_FORCE_ALL_PWRON";
45"PU_BIOS_USB_RECOVERY";
46"FM_BIOS_USB_RECOVERY";
47"CPU0_CLK_STRAP_SEL";
48"FM_PASSWORD_CLEAR_N";
49"FM_PRSNT_CPU1_N";
50"FM_PRSNT_CPU0_N";
%"UNIVERSAL_GND"
"1","(-550,400)","0","pure_quanta_power","I100";
;
CDS_LIB"pure_quanta_power"
HDL_POWER"GND";
"A"1;
%"Q_RES"
"1","(-750,550)","0","pure_quanta","I101";
;
LOCATION"R1206"
$SEC"1"
CDS_SEC"1"
VALUE"10K"
TOLERANCE"5%"
MATERIAL"CHIP"
PACK_TYPE"0402LF"
PART_NUMBER"TMP_QCS31002JB28"
WATTAGE"1/16W"
CDS_LIB"pure_quanta";
"B"
$PN"2"1;
"A"
$PN"1"41;
%"Q_RES"
"1","(-1825,550)","0","pure_quanta","I102";
;
LOCATION"R728"
$SEC"1"
CDS_SEC"1"
PACK_TYPE"0402LF"
PART_NUMBER"TMP_QCS31002JB28"
VALUE"10K"
TOLERANCE"5%"
MATERIAL"EMPTY"
WATTAGE"1/16W"
CDS_LIB"pure_quanta";
"B"
$PN"2"41;
"A"
$PN"1"47;
%"UNIVERSAL_GND"
"1","(-8400,1350)","5","pure_quanta_power","I116";
;
HDL_POWER"GND"
CDS_LIB"pure_quanta_power";
"A"20;
%"SW20S_DHNF10FTQTR"
"1","(-7700,1125)","0","pure_quanta","I117";
;
LOCATION"SW1"
$SEC"1"
CDS_SEC"1"
PART_TYPE"SMLF"
VALUE"SW20S_DHNF-10F-T-Q-TR"
PART_NUMBER"DHP00010F01"
MATERIAL"MECH"
CDS_LIB"pure_quanta"
NEEDS_NO_SIZE"TRUE"
CDS_LMAN_SYM_OUTLINE"-100,275,100,-275";
"10"
$PN"10"25;
"9"
$PN"9"2;
"20"
$PN"20"38;
"19"
$PN"19"35;
"18"
$PN"18"37;
"17"
$PN"17"28;
"16"
$PN"16"29;
"15"
$PN"15"27;
"8"
$PN"8"22;
"7"
$PN"7"24;
"6"
$PN"6"18;
"5"
$PN"5"21;
"14"
$PN"14"30;
"13"
$PN"13"31;
"12"
$PN"12"36;
"11"
$PN"11"32;
"4"
$PN"4"23;
"3"
$PN"3"20;
"2"
$PN"2"20;
"1"
$PN"1"20;
%"UNIVERSAL_GND"
"1","(-8400,950)","5","pure_quanta_power","I118";
;
HDL_POWER"GND"
CDS_LIB"pure_quanta_power";
"A"2;
%"Q_RES"
"1","(-1350,850)","0","pure_quanta","I126";
;
LOCATION"R743"
$SEC"1"
CDS_SEC"1"
VALUE"10K"
TOLERANCE"5%"
PACK_TYPE"0402LF"
PART_NUMBER"TMP_QCS31002JB28"
MATERIAL"CHIP"
WATTAGE"1/16W"
CDS_LIB"pure_quanta";
"B"
$PN"2"3;
"A"
$PN"1"42;
%"UNIVERSAL_POWER"
"1","(-925,1000)","0","pure_quanta_power","I127";
;
HDL_POWER"PVDD18_S5_P0"
CDS_LIB"pure_quanta_power";
"A"3;
%"Q_RES"
"1","(-8975,1100)","0","pure_quanta","I129";
;
LOCATION"R1508"
$SEC"1"
CDS_SEC"1"
VALUE"100"
CDS_LIB"pure_quanta"
WATTAGE"1/16W"
MATERIAL"CHIP"
PACK_TYPE"0402LF"
TOLERANCE"1%"
PART_NUMBER"TMP_QCS11002FB22";
"B"
$PN"2"18;
"A"
$PN"1"4;
%"UNIVERSAL_GND"
"1","(-9200,1100)","5","pure_quanta_power","I130";
;
HDL_POWER"GND"
CDS_LIB"pure_quanta_power";
"A"4;
%"Q_RES"
"1","(-6525,900)","0","pure_quanta","I132";
;
LOCATION"R1523"
$SEC"1"
CDS_SEC"1"
MATERIAL"EMPTY"
VALUE"33"
PACK_TYPE"0402LF"
PART_NUMBER"CS03302JB29"
TOLERANCE"5%"
WATTAGE"1/16W"
CDS_LIB"pure_quanta";
"B"
$PN"2"40;
"A"
$PN"1"38;
%"Q_RES"
"1","(-4375,3950)","1","pure_quanta","I133";
;
$LOCATION"R599"
CDS_LOCATION"R599"
$SEC"1"
CDS_SEC"1"
VALUE"100K"
MATERIAL"CHIP"
TOLERANCE"1%"
WATTAGE"1/16W"
PACK_TYPE"0402LF"
PART_NUMBER"TMP_QCS41002FB28"
CDS_LIB"pure_quanta";
"B"
$PN"2"33;
"A"
$PN"1"14;
%"Q_RES"
"1","(-7675,575)","0","pure_quanta","I134";
;
$LOCATION"R734"
CDS_LOCATION"R734"
$SEC"1"
CDS_SEC"1"
VALUE"0"
CDS_LIB"pure_quanta"
BOM_COST"MEM"
WATTAGE"1/16W"
MATERIAL"CHIP"
TOLERANCE"5%"
PART_NUMBER"CS00002JB38"
PACK_TYPE"0402LF"
ROOM"RST_CPU0_PLD_TO_DIMM";
"B"
$PN"2"28;
"A"
$PN"1"24;
%"Q_RES"
"1","(-7675,350)","0","pure_quanta","I135";
;
$LOCATION"R744"
CDS_LOCATION"R744"
$SEC"1"
CDS_SEC"1"
VALUE"0"
CDS_LIB"pure_quanta"
BOM_COST"MEM"
WATTAGE"1/16W"
MATERIAL"CHIP"
TOLERANCE"5%"
PART_NUMBER"CS00002JB38"
PACK_TYPE"0402LF"
ROOM"RST_CPU0_PLD_TO_DIMM";
"B"
$PN"2"37;
"A"
$PN"1"22;
%"SN74LVC1G07DBVR"
"1","(-7375,2075)","0","pure_quanta","I136";
;
$LOCATION"U124"
CDS_LOCATION"U124"
$SEC"1"
CDS_SEC"1"
MATERIAL"IC"
PART_NUMBER"AL1G0007024"
VALUE"SN74LVC1G07DBVR"
PACK_TYPE"SMLF"
NEEDS_NO_SIZE"TRUE"
CDS_LIB"pure_quanta";
"NC"
$PN"1"0;
"Y"
$PN"4"27;
"GND"
$PN"3"5;
"A"
$PN"2"21;
"VCC"
$PN"5"19;
%"UNIVERSAL_GND"
"1","(-7650,1875)","0","pure_quanta_power","I137";
;
CDS_LIB"pure_quanta_power"
HDL_POWER"GND";
"A"5;
%"UNIVERSAL_POWER"
"1","(-7650,2800)","2","pure_quanta_power","I138";
;
HDL_POWER"P3V3_STBY"
CDS_LIB"pure_quanta_power";
"A"19;
%"Q_CAP"
"1","(-7775,2450)","0","pure_quanta","I139";
;
$LOCATION"C693"
CDS_LOCATION"C693"
$SEC"1"
CDS_SEC"1"
VALUE"0.1UF"
VOLTAGE"25V"
PACK_TYPE"0402"
PART_NUMBER"CH4104K1B00"
MATERIAL"X7R"
CDS_LIB"pure_quanta"
TOLERANCE"10%";
"B"
$PN"2"6;
"A"
$PN"1"19;
%"UNIVERSAL_GND"
"1","(-7775,2175)","0","pure_quanta_power","I140";
;
HDL_POWER"GND"
CDS_LIB"pure_quanta_power";
"A"6;
%"UNIVERSAL_POWER"
"1","(-8275,6050)","2","pure_quanta_power","I37";
;
HDL_POWER"P1V8_STBY"
CDS_LIB"pure_quanta_power";
"A"7;
%"Q_RES"
"2","(-8275,5850)","2","pure_quanta","I38";
;
LOCATION"R1261"
$SEC"1"
CDS_SEC"1"
VALUE"10K"
PACK_TYPE"0402LF"
PART_NUMBER"TMP_QCS31002JB28"
TOLERANCE"5%"
MATERIAL"CHIP"
WATTAGE"1/16W"
CDS_LIB"pure_quanta";
"A"
$PN"1"7;
"B"
$PN"2"43;
%"Q_RES"
"2","(-8025,4150)","2","pure_quanta","I39";
;
LOCATION"R1263"
$SEC"1"
CDS_SEC"1"
VALUE"10K"
PACK_TYPE"0402LF"
PART_NUMBER"TMP_QCS31002JB28"
TOLERANCE"5%"
MATERIAL"CHIP"
WATTAGE"1/16W"
CDS_LIB"pure_quanta";
"A"
$PN"1"8;
"B"
$PN"2"44;
%"UNIVERSAL_POWER"
"1","(-8025,4350)","2","pure_quanta_power","I40";
;
HDL_POWER"P1V8_STBY"
CDS_LIB"pure_quanta_power";
"A"8;
%"Q_RES"
"2","(-8150,2600)","2","pure_quanta","I41";
;
LOCATION"R1262"
$SEC"1"
CDS_SEC"1"
VALUE"10K"
PACK_TYPE"0402LF"
PART_NUMBER"TMP_QCS31002JB28"
TOLERANCE"5%"
MATERIAL"CHIP"
WATTAGE"1/16W"
CDS_LIB"pure_quanta";
"A"
$PN"1"9;
"B"
$PN"2"26;
%"UNIVERSAL_POWER"
"1","(-8150,2800)","2","pure_quanta_power","I42";
;
HDL_POWER"P1V8_STBY"
CDS_LIB"pure_quanta_power";
"A"9;
%"UNIVERSAL_POWER"
"1","(-4925,5975)","2","pure_quanta_power","I43";
;
HDL_POWER"P1V8_STBY"
CDS_LIB"pure_quanta_power";
"A"10;
%"UNIVERSAL_GND"
"1","(-4150,5000)","2","pure_quanta_power","I45";
;
HDL_POWER"GND"
CDS_LIB"pure_quanta_power";
"A"11;
%"Q_RES"
"2","(-4150,5200)","2","pure_quanta","I46";
;
LOCATION"R1265"
$SEC"1"
CDS_SEC"1"
VALUE"10K"
PACK_TYPE"0402LF"
PART_NUMBER"TMP_QCS31002JB28"
TOLERANCE"5%"
MATERIAL"CHIP"
WATTAGE"1/16W"
CDS_LIB"pure_quanta";
"A"
$PN"1"46;
"B"
$PN"2"11;
%"UNIVERSAL_POWER"
"1","(-5100,2700)","2","pure_quanta_power","I48";
;
HDL_POWER"P1V8_STBY"
CDS_LIB"pure_quanta_power";
"A"12;
%"Q_RES"
"2","(-5100,2500)","2","pure_quanta","I49";
;
LOCATION"R1264"
$SEC"1"
CDS_SEC"1"
VALUE"1K"
CDS_LIB"pure_quanta"
WATTAGE"1/16W"
MATERIAL"CHIP"
PACK_TYPE"0402LF"
TOLERANCE"1%"
PART_NUMBER"TMP_QCS21002FB24";
"A"
$PN"1"12;
"B"
$PN"2"39;
%"UNIVERSAL_POWER"
"1","(-4875,4500)","2","pure_quanta_power","I53";
;
HDL_POWER"P1V8_STBY"
CDS_LIB"pure_quanta_power";
"A"13;
%"UNIVERSAL_GND"
"1","(-4375,3600)","2","pure_quanta_power","I56";
;
HDL_POWER"GND"
CDS_LIB"pure_quanta_power";
"A"14;
%"UNIVERSAL_POWER"
"1","(-1850,6050)","0","pure_quanta_power","I59";
;
HDL_POWER"P3V3_STBY"
CDS_LIB"pure_quanta_power";
"A"15;
%"Q_RES"
"2","(-1850,5800)","0","pure_quanta","I60";
;
LOCATION"R1356"
$SEC"1"
CDS_SEC"1"
PACK_TYPE"0402LF"
PART_NUMBER"TMP_QCS24702JB38"
VALUE"4.7K"
TOLERANCE"5%"
MATERIAL"CHIP"
WATTAGE"1/16W"
CDS_LIB"pure_quanta";
"A"
$PN"1"15;
"B"
$PN"2"50;
%"Q_RES"
"2","(-1850,4150)","0","pure_quanta","I63";
;
LOCATION"R1357"
$SEC"1"
CDS_SEC"1"
VALUE"2.2K"
PACK_TYPE"0402LF"
PART_NUMBER"CS22202JB07"
TOLERANCE"5%"
MATERIAL"CHIP"
WATTAGE"1/16W"
CDS_LIB"pure_quanta";
"A"
$PN"1"16;
"B"
$PN"2"49;
%"UNIVERSAL_POWER"
"1","(-1850,4400)","0","pure_quanta_power","I64";
;
HDL_POWER"P3V3_STBY"
CDS_LIB"pure_quanta_power";
"A"16;
%"Q_RES"
"2","(-1600,2650)","2","pure_quanta","I66";
;
LOCATION"R1358"
$SEC"1"
CDS_SEC"1"
VALUE"10K"
PACK_TYPE"0402LF"
PART_NUMBER"TMP_QCS31002JB28"
TOLERANCE"5%"
MATERIAL"CHIP"
WATTAGE"1/16W"
CDS_LIB"pure_quanta";
"A"
$PN"1"17;
"B"
$PN"2"48;
%"UNIVERSAL_POWER"
"1","(-1600,2850)","2","pure_quanta_power","I67";
;
HDL_POWER"P1V8_STBY"
CDS_LIB"pure_quanta_power";
"A"17;
%"Q_RES"
"2","(-4875,4300)","0","pure_quanta","I91";
;
LOCATION"R733"
$SEC"1"
CDS_SEC"1"
PACK_TYPE"0402LF"
MATERIAL"EMPTY"
TOLERANCE"1%"
VALUE"100"
WATTAGE"1/16W"
CDS_LIB"pure_quanta"
PART_NUMBER"TMP_QCS11002FB22";
"A"
$PN"1"13;
"B"
$PN"2"34;
%"Q_RES"
"2","(-4925,5775)","0","pure_quanta","I95";
;
LOCATION"R22"
$SEC"1"
CDS_SEC"1"
PACK_TYPE"0402LF"
VALUE"100"
TOLERANCE"1%"
MATERIAL"CHIP"
WATTAGE"1/16W"
PART_NUMBER"TMP_QCS11002FB22"
CDS_LIB"pure_quanta";
"A"
$PN"1"10;
"B"
$PN"2"45;
END.
